# ZAIUS-LBB-EVT2-X01-BOM-X03-20161116.xls — PWA BOM (bom)
| FOXCONN TECHNOLOGY GROUP |  |  |  |  |  |  |  |  |  |  |  |  |  |  |  |  |  |  |  |
| BILL OF MATERIAL |  |  |  |  |  |  |  |  |  |  |  |  |  |  |  |  |  |  |  |
| REV OF  BOM | X02 | CUSTOMER |  | DELL |  | CUSTOMER P/N |  | PWA P/N： | PWA DESCRIPTION | Peripheral Board,G,Zaius-LBB |  |  | PRODUCT CODE |  |  | PWA  REV |  | DATE |  |
| Sourcing (Single/Sole/Multi) | Critical Commodity (Y or N) | Component Class (1, 2, other) | Dell PSL (Y or N) | Line Item | Item Number | Foxconn P/N | Dell P/N | Part Description | Manufacturer  Full Name | Manufacturer  Part Number | Qty | RoHS Status | Location | CC Qual Build: | Qual by (Dell / ODM ?) | The Date of Change Part or Add 2nd Source | Configuration Identifier | Dell Comments | ODM Comments |
|  |  |  |  | 1 | 1 | 0101E7M00-000-G |  | PCB,Zaius-Lunch Box Board EVT2-X01,OSP,Red,4L,7.874*3.937,G | GOLD CIRCUIT ELECTRONICS LTD. | 0101E7M00-000-G | 1 |  | PCB |  |  |  |  |  |  |
|  | ND |  | Y(2) | 2 | 2 | 62111QR00-024-G |  | ECAP,100uF,+/-20%,100V,105C,G,SMD16*16.5,ESR<=170mOhm | PANASONIC INDUSTRIAL CO.,LTD. | EEEFK2A101AM | 2 |  | CE1,CE2 |  |  |  |  |  |  |
|  | ND | ND | Y(1) | 3 | 3 | 62011DA02-015-G |  | CAP,1uF,+/-10%,X7R,100V,G,SMD1206 | MURATA ELEC. NORTH AMERICA | GRM31CR72A105KA01K | 2 | Y | C29,C33 |  |  |  |  |  |  |
|  |  |  |  |  | 3 | 62011DA00-026-G |  | CAP,MLCC,1uF,+/-10%,X7R,100V,SMD1206,G | SAMSUNG | CL31B105KCHNNNE |  |  |  |  |  |  |  |  |  |
|  |  |  |  |  | 3 | 62011DA00-023-G |  | CAP,MLCC,1uF,+/-10%,X7R,100V,SMD1206,G | TAIYO | HMK316B7105KL-T |  |  |  |  |  |  |  |  |  |
|  | N |  | Y(1) | 4 | 4 | GRM31CR72A225KA73K |  | CAP,2.2uF,+/-10%,X7R,100V,G,SMD1206 | MURATA ELEC. NORTH AMERICA | GRM31CR72A225KA73K | 6 |  | C30,C31,C32,C34,C35,C36 |  |  |  |  |  |  |
|  | ND |  | Y(4) | 5 | 5 | 61015D800-017-G |  | RES,10KOhm,+/-5%,1W,G,SMD2512 | KOA SPEER ELECTRONICS, INC. | RK73BW3ATTE103J | 4 |  | R2,R3,R4,R5 |  |  |  |  |  |  |
|  |  |  |  |  | 5 | 61015D800-029-G |  | RES,10KOhm,+/-5%,1W,G,SMD2512 | VISHAY ENTER TECHNO LOGY.INC | CRCW251210K0JNEG |  |  |  |  |  |  |  |  |  |
|  | ND |  | Y(4) | 6 | 6 | 61011J500-017-G |  | RES,270 Ohm,+/-1%,1/16W,G,SMD0402 | KOA SPEER ELECTRONICS, INC. | RK73H1ETTP2700F | 2 | N | R6,R8 |  |  |  |  |  |  |
|  |  |  |  |  | 6 | 61011J500-029-G |  | RES,270 Ohm,+/-1%,1/16W,G,SMD040 | VISHAY ENTER TECHNO LOGY.INC | CRCW0402270RFKED |  |  |  |  |  |  |  |  |  |
|  | ND |  | N | 7 | 7 | 2A590Y300-HYM-G |  | NUT,CARBON STEEL,Tin Plating,G,82-450-22-016-01-RL | Fivetech Technology Inc. | 82-450-22-016-01-RL | 2 |  | H7,H8 |  |  |  |  |  |  |
|  | ND |  | N | 8 | 8 | 340312L00-G78-G |  | CONN,ISA,V/T,Bla,1.27mm,30u,G,SMD-48 | FCI CONNECTORS HONGKONG LTD. | 10122859-009LF | 2 |  | J1,J2 |  |  |  |  |  |  |
|  | N | other | N | 9 | 9 | 340604G00-600-G |  | CONN,Header,Friction,1X4,V/T,Bla,2.54mm,G,DIP-4 | FOXCONN TECHNOLOGY CO.,LTD. | HF1104E-P1 | 1 | Y | J5 |  |  |  |  |  |  |
|  |  |  |  | 10 | 10 | 3406AGU00-74S-G |  | CONN,Header,Power,R/A,Bla,14.99mm,G,DIP-6 | ANDERSON POWER PRODUCT | SBS75GPRBLK-BK | 1 |  | J6 |  |  |  |  |  |  |
